# BASEBOARD_FAB2 (Tioga Pass) — schematic netlist excerpt (pin names and nets, part order shuffled) for the footprints in the layout excerpt that follows; sources: Cadence DE-HDL packaged netlist, KiCad conversion of Wiwynn_Tioga_Pass_MB.brd

C2U26  CAP_A  1.0UF 6.3V 10% X6S  pkg 0402V  page 196 : A = P3V3_RTC_STBY ; B = GND
R1L41  RES  100.0 1% CHIP  pkg 0402  page 112 : A = P1V05_PCH_STBY ; B = XDP_PREQ_N
R3R7  RES  10.0 1% CHIP  pkg 0402  page 99 : A = SMB_DDR_DEF_SCL_G_R ; B = SMB_DDR_DEF_SCL_G

(kicad_pcb
	(version 20260206)
	(generator "pcbnew")
	(generator_version "10.0")
	(general
		(thickness 1.6)
		(legacy_teardrops no)
	)
	(paper "A4")
	(title_block
		(title "Wiwynn_Tioga_Pass_MB.brd")
		(comment 1 "Tioga Pass / footprints 3411-3413 of 4770")
	)
	(layers
		(0 "F.Cu" signal "TOP")
		(4 "In1.Cu" signal "L2GND")
		(6 "In2.Cu" signal "L3")
		(8 "In3.Cu" signal "L4GND")
		(10 "In4.Cu" signal "L5")
		(12 "In5.Cu" signal "L6GND")
		(14 "In6.Cu" signal "L7VCC")
		(16 "In7.Cu" signal "L8VCC")
		(18 "In8.Cu" signal "L9GND")
		(20 "In9.Cu" signal "L10")
		(22 "In10.Cu" signal "L11GND")
		(24 "In11.Cu" signal "L12")
		(26 "In12.Cu" signal "L13GND")
		(2 "B.Cu" signal "BOTTOM")
		(9 "F.Adhes" user "F.Adhesive")
		(11 "B.Adhes" user "B.Adhesive")
		(13 "F.Paste" user "Package Geometry/Pastemask Top")
		(15 "B.Paste" user "Package Geometry/Pastemask Bottom")
		(5 "F.SilkS" user "Ref Des/Silkscreen Top")
		(7 "B.SilkS" user "Ref Des/Silkscreen Bottom")
		(1 "F.Mask" user "Board Geometry/Soldermask Top")
		(3 "B.Mask" user "Board Geometry/Soldermask Bottom")
		(17 "Dwgs.User" user "User.Drawings")
		(19 "Cmts.User" user "User.Comments")
		(21 "Eco1.User" user "User.Eco1")
		(23 "Eco2.User" user "User.Eco2")
		(25 "Edge.Cuts" user "Board Geometry/Outline")
		(27 "Margin" user)
		(31 "F.CrtYd" user "Package Geometry/Place Bound Top")
		(29 "B.CrtYd" user "Package Geometry/Place Bound Bottom")
		(35 "F.Fab" user "Ref Des/Assembly Top")
		(33 "B.Fab" user "Ref Des/Assembly Bottom")
	)
	(footprint ""
		(layer "B.Cu")
		(at 330.116434 -62.456822 90)
		(property "Reference" "R3R7"
			(at 0 0 90)
			(layer "B.SilkS")
			(hide yes)
			(effects
				(font
					(size 1.27 1.27)
				)
				(justify mirror)
			)
		)
		(property "Value" ""
			(at 0 0 90)
			(layer "B.Fab")
			(effects
				(font
					(size 1.27 1.27)
				)
				(justify mirror)
			)
		)
		(duplicate_pad_numbers_are_jumpers no)
		(fp_poly
			(pts
				(xy 0.2794 -0.1016) (xy -0.2794 -0.1016) (xy -0.2794 0.9906) (xy 0.2794 0.9906)
			)
			(stroke
				(width 0)
				(type default)
			)
			(fill no)
			(layer "B.CrtYd")
		)
		(fp_line
			(start 0.2794 -0.1016)
			(end 0.2794 0.9906)
			(stroke
				(width 0.1)
				(type default)
			)
			(layer "B.Fab")
		)
		(fp_line
			(start -0.2794 -0.1016)
			(end 0.2794 -0.1016)
			(stroke
				(width 0.1)
				(type default)
			)
			(layer "B.Fab")
		)
		(fp_line
			(start 0.2794 0.9906)
			(end -0.2794 0.9906)
			(stroke
				(width 0.1)
				(type default)
			)
			(layer "B.Fab")
		)
		(fp_line
			(start -0.2794 0.9906)
			(end -0.2794 -0.1016)
			(stroke
				(width 0.1)
				(type default)
			)
			(layer "B.Fab")
		)
		(pad "1" smd rect
			(at 0 0 270)
			(size 0.508 0.508)
			(layers "B.Cu" "B.Mask" "B.Paste")
			(net "SMB_DDR_DEF_SCL_G_R")
		)
		(pad "2" smd rect
			(at 0 0.889 270)
			(size 0.508 0.508)
			(layers "B.Cu" "B.Mask" "B.Paste")
			(net "SMB_DDR_DEF_SCL_G")
		)
		(zone
			(layer "B.Cu")
			(hatch none 0.5)
			(connect_pads
				(clearance 0)
			)
			(min_thickness 0.25)
			(keepout
				(tracks allowed)
				(vias not_allowed)
				(pads allowed)
				(copperpour not_allowed)
				(footprints allowed)
			)
			(placement
				(enabled no)
				(sheetname "")
			)
			(fill
				(thermal_gap 0.5)
				(thermal_bridge_width 0.5)
				(island_removal_mode 0)
			)
			(polygon
				(pts
					(xy 330.370434 -62.710822) (xy 330.370434 -62.202822) (xy 330.751434 -62.202822) (xy 330.751434 -62.710822)
				)
			)
		)
		(zone
			(layer "B.Cu")
			(hatch none 0.5)
			(connect_pads
				(clearance 0)
			)
			(min_thickness 0.25)
			(keepout
				(tracks not_allowed)
				(vias allowed)
				(pads allowed)
				(copperpour not_allowed)
				(footprints allowed)
			)
			(placement
				(enabled no)
				(sheetname "")
			)
			(fill
				(thermal_gap 0.5)
				(thermal_bridge_width 0.5)
				(island_removal_mode 0)
			)
			(polygon
				(pts
					(xy 330.751434 -62.710822) (xy 330.751434 -62.202822) (xy 330.370434 -62.202822) (xy 330.370434 -62.710822)
				)
			)
		)
	)
	(footprint ""
		(layer "B.Cu")
		(at 462.801208 -136.525254 90)
		(property "Reference" "R1L41"
			(at 0 0 90)
			(layer "B.SilkS")
			(hide yes)
			(effects
				(font
					(size 1.27 1.27)
				)
				(justify mirror)
			)
		)
		(property "Value" ""
			(at 0 0 90)
			(layer "B.Fab")
			(effects
				(font
					(size 1.27 1.27)
				)
				(justify mirror)
			)
		)
		(duplicate_pad_numbers_are_jumpers no)
		(fp_poly
			(pts
				(xy 0.2794 -0.1016) (xy -0.2794 -0.1016) (xy -0.2794 0.9906) (xy 0.2794 0.9906)
			)
			(stroke
				(width 0)
				(type default)
			)
			(fill no)
			(layer "B.CrtYd")
		)
		(fp_line
			(start 0.2794 -0.1016)
			(end 0.2794 0.9906)
			(stroke
				(width 0.1)
				(type default)
			)
			(layer "B.Fab")
		)
		(fp_line
			(start -0.2794 -0.1016)
			(end 0.2794 -0.1016)
			(stroke
				(width 0.1)
				(type default)
			)
			(layer "B.Fab")
		)
		(fp_line
			(start 0.2794 0.9906)
			(end -0.2794 0.9906)
			(stroke
				(width 0.1)
				(type default)
			)
			(layer "B.Fab")
		)
		(fp_line
			(start -0.2794 0.9906)
			(end -0.2794 -0.1016)
			(stroke
				(width 0.1)
				(type default)
			)
			(layer "B.Fab")
		)
		(pad "1" smd rect
			(at 0 0 270)
			(size 0.508 0.508)
			(layers "B.Cu" "B.Mask" "B.Paste")
			(net "P1V05_PCH_STBY")
		)
		(pad "2" smd rect
			(at 0 0.889 270)
			(size 0.508 0.508)
			(layers "B.Cu" "B.Mask" "B.Paste")
			(net "XDP_PREQ_N")
		)
		(zone
			(layer "B.Cu")
			(hatch none 0.5)
			(connect_pads
				(clearance 0)
			)
			(min_thickness 0.25)
			(keepout
				(tracks allowed)
				(vias not_allowed)
				(pads allowed)
				(copperpour not_allowed)
				(footprints allowed)
			)
			(placement
				(enabled no)
				(sheetname "")
			)
			(fill
				(thermal_gap 0.5)
				(thermal_bridge_width 0.5)
				(island_removal_mode 0)
			)
			(polygon
				(pts
					(xy 463.055208 -136.779254) (xy 463.055208 -136.271254) (xy 463.436208 -136.271254) (xy 463.436208 -136.779254)
				)
			)
		)
		(zone
			(layer "B.Cu")
			(hatch none 0.5)
			(connect_pads
				(clearance 0)
			)
			(min_thickness 0.25)
			(keepout
				(tracks not_allowed)
				(vias allowed)
				(pads allowed)
				(copperpour not_allowed)
				(footprints allowed)
			)
			(placement
				(enabled no)
				(sheetname "")
			)
			(fill
				(thermal_gap 0.5)
				(thermal_bridge_width 0.5)
				(island_removal_mode 0)
			)
			(polygon
				(pts
					(xy 463.436208 -136.779254) (xy 463.436208 -136.271254) (xy 463.055208 -136.271254) (xy 463.055208 -136.779254)
				)
			)
		)
	)
	(footprint ""
		(layer "B.Cu")
		(at 447.6242 -12.2174 180)
		(property "Reference" "C2U26"
			(at 0 0 0)
			(layer "B.SilkS")
			(hide yes)
			(effects
				(font
					(size 1.27 1.27)
				)
				(justify mirror)
			)
		)
		(property "Value" ""
			(at 0 0 0)
			(layer "B.Fab")
			(effects
				(font
					(size 1.27 1.27)
				)
				(justify mirror)
			)
		)
		(duplicate_pad_numbers_are_jumpers no)
		(fp_poly
			(pts
				(xy -0.3048 -0.1016) (xy -0.3048 0.9906) (xy 0.3048 0.9906) (xy 0.3048 -0.1016)
			)
			(stroke
				(width 0)
				(type default)
			)
			(fill no)
			(layer "B.CrtYd")
		)
		(fp_line
			(start 0.3048 0.9906)
			(end -0.3048 0.9906)
			(stroke
				(width 0.1)
				(type default)
			)
			(layer "B.Fab")
		)
		(fp_line
			(start 0.3048 -0.1016)
			(end 0.3048 0.9906)
			(stroke
				(width 0.1)
				(type default)
			)
			(layer "B.Fab")
		)
		(fp_line
			(start -0.3048 0.9906)
			(end -0.3048 -0.1016)
			(stroke
				(width 0.1)
				(type default)
			)
			(layer "B.Fab")
		)
		(fp_line
			(start -0.3048 -0.1016)
			(end 0.3048 -0.1016)
			(stroke
				(width 0.1)
				(type default)
			)
			(layer "B.Fab")
		)
		(pad "1" smd rect
			(at 0 0)
			(size 0.508 0.508)
			(layers "B.Cu" "B.Mask" "B.Paste")
			(net "P3V3_RTC_STBY")
		)
		(pad "2" smd rect
			(at 0 0.889)
			(size 0.508 0.508)
			(layers "B.Cu" "B.Mask" "B.Paste")
			(net "GND")
		)
		(zone
			(layer "B.Cu")
			(hatch none 0.5)
			(connect_pads
				(clearance 0)
			)
			(min_thickness 0.25)
			(keepout
				(tracks not_allowed)
				(vias allowed)
				(pads allowed)
				(copperpour not_allowed)
				(footprints allowed)
			)
			(placement
				(enabled no)
				(sheetname "")
			)
			(fill
				(thermal_gap 0.5)
				(thermal_bridge_width 0.5)
				(island_removal_mode 0)
			)
			(polygon
				(pts
					(xy 447.3702 -12.8524) (xy 447.8782 -12.8524) (xy 447.8782 -12.4714) (xy 447.3702 -12.4714)
				)
			)
		)
		(zone
			(layer "B.Cu")
			(hatch none 0.5)
			(connect_pads
				(clearance 0)
			)
			(min_thickness 0.25)
			(keepout
				(tracks allowed)
				(vias not_allowed)
				(pads allowed)
				(copperpour not_allowed)
				(footprints allowed)
			)
			(placement
				(enabled no)
				(sheetname "")
			)
			(fill
				(thermal_gap 0.5)
				(thermal_bridge_width 0.5)
				(island_removal_mode 0)
			)
			(polygon
				(pts
					(xy 447.3702 -12.4714) (xy 447.8782 -12.4714) (xy 447.8782 -12.8524) (xy 447.3702 -12.8524)
				)
			)
		)
	)
)
